# S9S_MB_2U (Grand Teton) — schematic netlist excerpt (pin names and nets, part order shuffled) for the footprints in the layout excerpt that follows; sources: Cadence DE-HDL packaged netlist, KiCad conversion of 03242023_DA0F0TMBIJ0_F0T_Motherboard_J_brd_V01_OCP.brd

R565  Q_RES  22 1% CHIP  pkg 0402LF  page 209 : A = CLK_100M_OCP_SFF_1_R_DP ; B = CLK_100M_OCP_SFF_1_DP
C896  Q_CAP_DIFFBUS  DIFF BUS_0.22UF 6.3V 20% X6S  pkg C0201  page 174 : \1\ = P5E_CPU0_PE3_TX_C_DN<2> ; \2\ = P5E_CPU0_PE3_TX_DN<2>

Q106  MOSFET_NCH_DUAL  PJT138K IC  pkg SOT363XD  page 147
  S1  = GND
  G1  = GPU_WP_HW_CTRL_N
  D1  = GPU_WP_HW_CTRL_ISO

(kicad_pcb
	(version 20260206)
	(generator "pcbnew")
	(generator_version "10.0")
	(general
		(thickness 1.6)
		(legacy_teardrops no)
	)
	(paper "A4")
	(title_block
		(title "03242023_DA0F0TMBIJ0_F0T_Motherboard_J_brd_V01_OCP.brd")
		(comment 1 "Grand Teton / footprints 2641-2643 of 6105")
	)
	(layers
		(0 "F.Cu" signal "TOP")
		(4 "In1.Cu" signal "GND")
		(6 "In2.Cu" signal "IN1")
		(8 "In3.Cu" signal "GND1")
		(10 "In4.Cu" signal "IN2")
		(12 "In5.Cu" signal "GND2")
		(14 "In6.Cu" signal "IN3")
		(16 "In7.Cu" signal "GND3")
		(18 "In8.Cu" signal "VCC")
		(20 "In9.Cu" signal "VCC1")
		(22 "In10.Cu" signal "GND4")
		(24 "In11.Cu" signal "IN4")
		(26 "In12.Cu" signal "GND5")
		(28 "In13.Cu" signal "IN5")
		(30 "In14.Cu" signal "GND6")
		(32 "In15.Cu" signal "IN6")
		(34 "In16.Cu" signal "GND7")
		(2 "B.Cu" signal "BOTTOM")
		(9 "F.Adhes" user "F.Adhesive")
		(11 "B.Adhes" user "B.Adhesive")
		(13 "F.Paste" user "Package Geometry/Pastemask Top")
		(15 "B.Paste" user "Package Geometry/Pastemask Bottom")
		(5 "F.SilkS" user "Ref Des/Silkscreen Top")
		(7 "B.SilkS" user "Ref Des/Silkscreen Bottom")
		(1 "F.Mask" user "Board Geometry/Soldermask Top")
		(3 "B.Mask" user "Board Geometry/Soldermask Bottom")
		(17 "Dwgs.User" user "User.Drawings")
		(19 "Cmts.User" user "User.Comments")
		(21 "Eco1.User" user "User.Eco1")
		(23 "Eco2.User" user "User.Eco2")
		(25 "Edge.Cuts" user "Board Geometry/Outline")
		(27 "Margin" user)
		(31 "F.CrtYd" user "Package Geometry/Place Bound Top")
		(29 "B.CrtYd" user "Package Geometry/Place Bound Bottom")
		(35 "F.Fab" user "Ref Des/Assembly Top")
		(33 "B.Fab" user "Ref Des/Assembly Bottom")
	)
	(footprint ""
		(layer "F.Cu")
		(at 228.764592 -125.297946 180)
		(property "Reference" "R565"
			(at 0 0 180)
			(layer "F.SilkS")
			(hide yes)
			(effects
				(font
					(size 1.27 1.27)
				)
			)
		)
		(property "Value" ""
			(at 0 0 180)
			(layer "F.Fab")
			(effects
				(font
					(size 1.27 1.27)
				)
			)
		)
		(duplicate_pad_numbers_are_jumpers no)
		(fp_line
			(start 0.7874 0.4064)
			(end -0.7874 0.4064)
			(stroke
				(width 0.1524)
				(type default)
			)
			(layer "F.SilkS")
		)
		(fp_line
			(start 0.7874 -0.050546)
			(end 0.7874 0.4064)
			(stroke
				(width 0.1524)
				(type default)
			)
			(layer "F.SilkS")
		)
		(fp_line
			(start -0.429768 -0.4064)
			(end 0.520192 -0.4064)
			(stroke
				(width 0.1524)
				(type default)
			)
			(layer "F.SilkS")
		)
		(fp_line
			(start -0.7874 0.4064)
			(end -0.7874 -0.083566)
			(stroke
				(width 0.1524)
				(type default)
			)
			(layer "F.SilkS")
		)
		(fp_line
			(start 0.67945 0.3048)
			(end 0.120396 0.3048)
			(stroke
				(width 0.1)
				(type default)
			)
			(layer "F.Fab")
		)
		(fp_line
			(start 0.67945 -0.3048)
			(end 0.67945 0.3048)
			(stroke
				(width 0.1)
				(type default)
			)
			(layer "F.Fab")
		)
		(fp_line
			(start 0.12065 -0.2794)
			(end 0.12065 -0.3048)
			(stroke
				(width 0.1)
				(type default)
			)
			(layer "F.Fab")
		)
		(fp_line
			(start 0.12065 -0.3048)
			(end 0.67945 -0.3048)
			(stroke
				(width 0.1)
				(type default)
			)
			(layer "F.Fab")
		)
		(fp_line
			(start 0.120396 0.3048)
			(end 0.120396 0.2794)
			(stroke
				(width 0.1)
				(type default)
			)
			(layer "F.Fab")
		)
		(fp_line
			(start 0.120396 0.2794)
			(end -0.12065 0.2794)
			(stroke
				(width 0.1)
				(type default)
			)
			(layer "F.Fab")
		)
		(fp_line
			(start -0.12065 0.3048)
			(end -0.67945 0.3048)
			(stroke
				(width 0.1)
				(type default)
			)
			(layer "F.Fab")
		)
		(fp_line
			(start -0.12065 0.2794)
			(end -0.12065 0.3048)
			(stroke
				(width 0.1)
				(type default)
			)
			(layer "F.Fab")
		)
		(fp_line
			(start -0.12065 -0.2794)
			(end 0.12065 -0.2794)
			(stroke
				(width 0.1)
				(type default)
			)
			(layer "F.Fab")
		)
		(fp_line
			(start -0.12065 -0.305054)
			(end -0.12065 -0.2794)
			(stroke
				(width 0.1)
				(type default)
			)
			(layer "F.Fab")
		)
		(fp_line
			(start -0.67945 0.3048)
			(end -0.67945 -0.305054)
			(stroke
				(width 0.1)
				(type default)
			)
			(layer "F.Fab")
		)
		(fp_line
			(start -0.67945 -0.305054)
			(end -0.12065 -0.305054)
			(stroke
				(width 0.1)
				(type default)
			)
			(layer "F.Fab")
		)
		(pad "1" smd circle
			(at -0.40005 0 180)
			(size 0 0)
			(layers "F.Cu" "F.Mask" "F.Paste")
			(net "CLK_100M_OCP_SFF_1_R_DP")
		)
		(pad "2" smd circle
			(at 0.40005 0 180)
			(size 0 0)
			(layers "F.Cu" "F.Mask" "F.Paste")
			(net "CLK_100M_OCP_SFF_1_DP")
		)
	)
	(footprint ""
		(layer "F.Cu")
		(at 428.179992 -401.655534)
		(property "Reference" "Q106"
			(at -1.071372 -3.402584 0)
			(unlocked yes)
			(layer "F.SilkS")
			(effects
				(font
					(size 0.7874 0.5842)
					(thickness 0.1524)
				)
				(justify left)
			)
		)
		(property "Value" ""
			(at 0 0 0)
			(layer "F.Fab")
			(effects
				(font
					(size 1.27 1.27)
				)
			)
		)
		(duplicate_pad_numbers_are_jumpers no)
		(fp_line
			(start -1.332738 -1.100074)
			(end -0.4826 -1.100074)
			(stroke
				(width 0.1524)
				(type default)
			)
			(layer "F.SilkS")
		)
		(fp_line
			(start -1.332738 1.100074)
			(end -1.332738 -1.100074)
			(stroke
				(width 0.1524)
				(type default)
			)
			(layer "F.SilkS")
		)
		(fp_line
			(start -0.4826 -1.100074)
			(end 0 -0.541274)
			(stroke
				(width 0.1524)
				(type default)
			)
			(layer "F.SilkS")
		)
		(fp_line
			(start 0 -0.541274)
			(end 0.4826 -1.100074)
			(stroke
				(width 0.1524)
				(type default)
			)
			(layer "F.SilkS")
		)
		(fp_line
			(start 0.4826 -1.100074)
			(end 1.332738 -1.100074)
			(stroke
				(width 0.1524)
				(type default)
			)
			(layer "F.SilkS")
		)
		(fp_line
			(start 1.332738 -1.100074)
			(end 1.332738 1.100074)
			(stroke
				(width 0.1524)
				(type default)
			)
			(layer "F.SilkS")
		)
		(fp_line
			(start 1.332738 1.100074)
			(end -1.332738 1.100074)
			(stroke
				(width 0.1524)
				(type default)
			)
			(layer "F.SilkS")
		)
		(fp_poly
			(pts
				(xy -0.672592 -2.035302) (xy -1.02362 -1.333246) (xy -1.374648 -2.035302)
			)
			(stroke
				(width 0)
				(type default)
			)
			(fill yes)
			(layer "F.SilkS")
		)
		(fp_line
			(start -0.674878 -1.100074)
			(end 0.674878 -1.100074)
			(stroke
				(width 0.1)
				(type default)
			)
			(layer "F.Fab")
		)
		(fp_line
			(start -0.674878 1.100074)
			(end -0.674878 -1.100074)
			(stroke
				(width 0.1)
				(type default)
			)
			(layer "F.Fab")
		)
		(fp_line
			(start 0.674878 -1.100074)
			(end 0.674878 1.100074)
			(stroke
				(width 0.1)
				(type default)
			)
			(layer "F.Fab")
		)
		(fp_line
			(start 0.674878 1.100074)
			(end -0.674878 1.100074)
			(stroke
				(width 0.1)
				(type default)
			)
			(layer "F.Fab")
		)
		(fp_poly
			(pts
				(xy -2.2352 -0.298958) (xy -2.2352 -1.001014) (xy -1.533144 -0.649986)
			)
			(stroke
				(width 0)
				(type default)
			)
			(fill yes)
			(layer "F.Fab")
		)
		(pad "1" smd rect
			(at -0.94996 -0.649986 90)
			(size 0.4318 0.508)
			(layers "F.Cu" "F.Mask" "F.Paste")
			(net "GND")
		)
		(pad "2" smd rect
			(at -0.94996 0 90)
			(size 0.4318 0.508)
			(layers "F.Cu" "F.Mask" "F.Paste")
			(net "GPU_WP_HW_CTRL_N")
		)
		(pad "3" smd rect
			(at -0.94996 0.649986 90)
			(size 0.4318 0.508)
			(layers "F.Cu" "F.Mask" "F.Paste")
			(net "Net_27")
		)
		(pad "4" smd rect
			(at 0.94996 0.649986 90)
			(size 0.4318 0.508)
			(layers "F.Cu" "F.Mask" "F.Paste")
			(net "Net_25")
		)
		(pad "5" smd rect
			(at 0.94996 0 90)
			(size 0.4318 0.508)
			(layers "F.Cu" "F.Mask" "F.Paste")
			(net "Net_26")
		)
		(pad "6" smd rect
			(at 0.94996 -0.649986 90)
			(size 0.4318 0.508)
			(layers "F.Cu" "F.Mask" "F.Paste")
			(net "GPU_WP_HW_CTRL_ISO")
		)
	)
	(footprint ""
		(layer "F.Cu")
		(at 412.56585 -408.517344 -90)
		(property "Reference" "C896"
			(at 0 0 270)
			(layer "F.SilkS")
			(hide yes)
			(effects
				(font
					(size 1.27 1.27)
				)
			)
		)
		(property "Value" ""
			(at 0 0 270)
			(layer "F.Fab")
			(effects
				(font
					(size 1.27 1.27)
				)
			)
		)
		(duplicate_pad_numbers_are_jumpers no)
		(fp_line
			(start -0.299974 0.150114)
			(end -0.299974 -0.150114)
			(stroke
				(width 0.1)
				(type default)
			)
			(layer "F.Fab")
		)
		(fp_line
			(start 0.299974 0.150114)
			(end -0.299974 0.150114)
			(stroke
				(width 0.1)
				(type default)
			)
			(layer "F.Fab")
		)
		(fp_line
			(start -0.299974 -0.150114)
			(end 0.299974 -0.150114)
			(stroke
				(width 0.1)
				(type default)
			)
			(layer "F.Fab")
		)
		(fp_line
			(start 0.299974 -0.150114)
			(end 0.299974 0.150114)
			(stroke
				(width 0.1)
				(type default)
			)
			(layer "F.Fab")
		)
		(pad "1" smd rect
			(at -0.2667 0 270)
			(size 0.3048 0.381)
			(layers "F.Cu" "F.Mask" "F.Paste")
			(net "P5E_CPU0_PE3_TX_C_DN<2>")
		)
		(pad "2" smd rect
			(at 0.2667 0 270)
			(size 0.3048 0.381)
			(layers "F.Cu" "F.Mask" "F.Paste")
			(net "P5E_CPU0_PE3_TX_DN<2>")
		)
	)
)
